(kicad_pcb
	(version 20260206)
	(generator "pcbnew")
	(generator_version "10.0")
	(general
		(thickness 1.6)
		(legacy_teardrops no)
	)
	(paper "A4")
	(title_block
		(title "03242023_DA0F0TMBIJ0_F0T_Motherboard_J_brd_V01_OCP.brd")
		(comment 1 "Grand Teton / footprint 1065 of 6105 (J26), pads 113-224 of 291")
	)
	(layers
		(0 "F.Cu" signal "TOP")
		(4 "In1.Cu" signal "GND")
		(6 "In2.Cu" signal "IN1")
		(8 "In3.Cu" signal "GND1")
		(10 "In4.Cu" signal "IN2")
		(12 "In5.Cu" signal "GND2")
		(14 "In6.Cu" signal "IN3")
		(16 "In7.Cu" signal "GND3")
		(18 "In8.Cu" signal "VCC")
		(20 "In9.Cu" signal "VCC1")
		(22 "In10.Cu" signal "GND4")
		(24 "In11.Cu" signal "IN4")
		(26 "In12.Cu" signal "GND5")
		(28 "In13.Cu" signal "IN5")
		(30 "In14.Cu" signal "GND6")
		(32 "In15.Cu" signal "IN6")
		(34 "In16.Cu" signal "GND7")
		(2 "B.Cu" signal "BOTTOM")
		(9 "F.Adhes" user "F.Adhesive")
		(11 "B.Adhes" user "B.Adhesive")
		(13 "F.Paste" user "Package Geometry/Pastemask Top")
		(15 "B.Paste" user "Package Geometry/Pastemask Bottom")
		(5 "F.SilkS" user "Ref Des/Silkscreen Top")
		(7 "B.SilkS" user "Ref Des/Silkscreen Bottom")
		(1 "F.Mask" user "Board Geometry/Soldermask Top")
		(3 "B.Mask" user "Board Geometry/Soldermask Bottom")
		(17 "Dwgs.User" user "User.Drawings")
		(19 "Cmts.User" user "User.Comments")
		(21 "Eco1.User" user "User.Eco1")
		(23 "Eco2.User" user "User.Eco2")
		(25 "Edge.Cuts" user "Board Geometry/Outline")
		(27 "Margin" user)
		(31 "F.CrtYd" user "Package Geometry/Place Bound Top")
		(29 "B.CrtYd" user "Package Geometry/Place Bound Bottom")
		(35 "F.Fab" user "Ref Des/Assembly Top")
		(33 "B.Fab" user "Ref Des/Assembly Bottom")
	)
	(footprint ""
		(layer "F.Cu")
		(at 160.86328 -258.091686)
		(property "Reference" "J26"
			(at -3.683 -81.702148 0)
			(unlocked yes)
			(layer "F.SilkS")
			(effects
				(font
					(size 0.7874 0.5842)
					(thickness 0.1524)
				)
				(justify left)
			)
		)
		(property "Value" ""
			(at 0 0 0)
			(layer "F.Fab")
			(effects
				(font
					(size 1.27 1.27)
				)
			)
		)
		(duplicate_pad_numbers_are_jumpers no)
		(pad "113" smd rect
			(at -2.050034 36.975034 270)
			(size 0.519938 1.4986)
			(layers "F.Cu" "F.Mask" "F.Paste")
			(net "M_E_CPU1_SB_DQ<9>")
		)
		(pad "114" smd rect
			(at -2.050034 37.824918 270)
			(size 0.519938 1.4986)
			(layers "F.Cu" "F.Mask" "F.Paste")
			(net "GND")
		)
		(pad "115" smd rect
			(at -2.050034 38.675056 270)
			(size 0.519938 1.4986)
			(layers "F.Cu" "F.Mask" "F.Paste")
			(net "M_E_CPU1_SB_DQS_DP<1>")
		)
		(pad "116" smd rect
			(at -2.050034 39.52494 270)
			(size 0.519938 1.4986)
			(layers "F.Cu" "F.Mask" "F.Paste")
			(net "M_E_CPU1_SB_DQS_DN<1>")
		)
		(pad "117" smd rect
			(at -2.050034 40.375078 270)
			(size 0.519938 1.4986)
			(layers "F.Cu" "F.Mask" "F.Paste")
			(net "GND")
		)
		(pad "118" smd rect
			(at -2.050034 41.224962 270)
			(size 0.519938 1.4986)
			(layers "F.Cu" "F.Mask" "F.Paste")
			(net "M_E_CPU1_SB_DQ<12>")
		)
		(pad "119" smd rect
			(at -2.050034 42.0751 270)
			(size 0.519938 1.4986)
			(layers "F.Cu" "F.Mask" "F.Paste")
			(net "GND")
		)
		(pad "120" smd rect
			(at -2.050034 42.924984 270)
			(size 0.519938 1.4986)
			(layers "F.Cu" "F.Mask" "F.Paste")
			(net "M_E_CPU1_SB_DQ<13>")
		)
		(pad "121" smd rect
			(at -2.050034 43.775122 270)
			(size 0.519938 1.4986)
			(layers "F.Cu" "F.Mask" "F.Paste")
			(net "GND")
		)
		(pad "122" smd rect
			(at -2.050034 44.625006 270)
			(size 0.519938 1.4986)
			(layers "F.Cu" "F.Mask" "F.Paste")
			(net "M_E_CPU1_SB_DQ<16>")
		)
		(pad "123" smd rect
			(at -2.050034 45.47489 270)
			(size 0.519938 1.4986)
			(layers "F.Cu" "F.Mask" "F.Paste")
			(net "GND")
		)
		(pad "124" smd rect
			(at -2.050034 46.325028 270)
			(size 0.519938 1.4986)
			(layers "F.Cu" "F.Mask" "F.Paste")
			(net "M_E_CPU1_SB_DQ<17>")
		)
		(pad "125" smd rect
			(at -2.050034 47.174912 270)
			(size 0.519938 1.4986)
			(layers "F.Cu" "F.Mask" "F.Paste")
			(net "GND")
		)
		(pad "126" smd rect
			(at -2.050034 48.02505 270)
			(size 0.519938 1.4986)
			(layers "F.Cu" "F.Mask" "F.Paste")
			(net "M_E_CPU1_SB_DQS_DP<2>")
		)
		(pad "127" smd rect
			(at -2.050034 48.874934 270)
			(size 0.519938 1.4986)
			(layers "F.Cu" "F.Mask" "F.Paste")
			(net "M_E_CPU1_SB_DQS_DN<2>")
		)
		(pad "128" smd rect
			(at -2.050034 49.725072 270)
			(size 0.519938 1.4986)
			(layers "F.Cu" "F.Mask" "F.Paste")
			(net "GND")
		)
		(pad "129" smd rect
			(at -2.050034 50.574956 270)
			(size 0.519938 1.4986)
			(layers "F.Cu" "F.Mask" "F.Paste")
			(net "M_E_CPU1_SB_DQ<20>")
		)
		(pad "130" smd rect
			(at -2.050034 51.425094 270)
			(size 0.519938 1.4986)
			(layers "F.Cu" "F.Mask" "F.Paste")
			(net "GND")
		)
		(pad "131" smd rect
			(at -2.050034 52.274978 270)
			(size 0.519938 1.4986)
			(layers "F.Cu" "F.Mask" "F.Paste")
			(net "M_E_CPU1_SB_DQ<21>")
		)
		(pad "132" smd rect
			(at -2.050034 53.125116 270)
			(size 0.519938 1.4986)
			(layers "F.Cu" "F.Mask" "F.Paste")
			(net "GND")
		)
		(pad "133" smd rect
			(at -2.050034 53.975 270)
			(size 0.519938 1.4986)
			(layers "F.Cu" "F.Mask" "F.Paste")
			(net "M_E_CPU1_SB_DQ<24>")
		)
		(pad "134" smd rect
			(at -2.050034 54.824884 270)
			(size 0.519938 1.4986)
			(layers "F.Cu" "F.Mask" "F.Paste")
			(net "GND")
		)
		(pad "135" smd rect
			(at -2.050034 55.675022 270)
			(size 0.519938 1.4986)
			(layers "F.Cu" "F.Mask" "F.Paste")
			(net "M_E_CPU1_SB_DQ<25>")
		)
		(pad "136" smd rect
			(at -2.050034 56.524906 270)
			(size 0.519938 1.4986)
			(layers "F.Cu" "F.Mask" "F.Paste")
			(net "GND")
		)
		(pad "137" smd rect
			(at -2.050034 57.375044 270)
			(size 0.519938 1.4986)
			(layers "F.Cu" "F.Mask" "F.Paste")
			(net "M_E_CPU1_SB_DQS_DP<3>")
		)
		(pad "138" smd rect
			(at -2.050034 58.224928 270)
			(size 0.519938 1.4986)
			(layers "F.Cu" "F.Mask" "F.Paste")
			(net "M_E_CPU1_SB_DQS_DN<3>")
		)
		(pad "139" smd rect
			(at -2.050034 59.075066 270)
			(size 0.519938 1.4986)
			(layers "F.Cu" "F.Mask" "F.Paste")
			(net "GND")
		)
		(pad "140" smd rect
			(at -2.050034 59.92495 270)
			(size 0.519938 1.4986)
			(layers "F.Cu" "F.Mask" "F.Paste")
			(net "M_E_CPU1_SB_DQ<28>")
		)
		(pad "141" smd rect
			(at -2.050034 60.775088 270)
			(size 0.519938 1.4986)
			(layers "F.Cu" "F.Mask" "F.Paste")
			(net "GND")
		)
		(pad "142" smd rect
			(at -2.050034 61.624972 270)
			(size 0.519938 1.4986)
			(layers "F.Cu" "F.Mask" "F.Paste")
			(net "M_E_CPU1_SB_DQ<29>")
		)
		(pad "143" smd rect
			(at -2.050034 62.47511 270)
			(size 0.519938 1.4986)
			(layers "F.Cu" "F.Mask" "F.Paste")
			(net "GND")
		)
		(pad "144" smd rect
			(at -2.050034 63.324994 270)
			(size 0.519938 1.4986)
			(layers "F.Cu" "F.Mask" "F.Paste")
			(net "TP_CHE_CPU1_DIMM2_FRU_1")
		)
		(pad "145" smd rect
			(at 2.050034 -63.324994 270)
			(size 0.519938 1.4986)
			(layers "F.Cu" "F.Mask" "F.Paste")
			(net "P12V_S3_AUX_CPU1_NVDIMM")
		)
		(pad "146" smd rect
			(at 2.050034 -62.47511 270)
			(size 0.519938 1.4986)
			(layers "F.Cu" "F.Mask" "F.Paste")
			(net "P12V_S3_AUX_CPU1_NVDIMM")
		)
		(pad "147" smd rect
			(at 2.050034 -61.624972 270)
			(size 0.519938 1.4986)
			(layers "F.Cu" "F.Mask" "F.Paste")
			(net "PWRGD_CHE_CPU1_DIMM2")
		)
		(pad "148" smd rect
			(at 2.050034 -60.775088 270)
			(size 0.519938 1.4986)
			(layers "F.Cu" "F.Mask" "F.Paste")
			(net "PD_CHE_CPU1_DIMM2_SAA")
		)
		(pad "149" smd rect
			(at 2.050034 -59.92495 270)
			(size 0.519938 1.4986)
			(layers "F.Cu" "F.Mask" "F.Paste")
			(net "TP_CHE_CPU1_DIMM2_FRU_2")
		)
		(pad "150" smd rect
			(at 2.050034 -59.075066 270)
			(size 0.519938 1.4986)
			(layers "F.Cu" "F.Mask" "F.Paste")
			(net "TP_CHE_CPU1_DIMM2_FRU_3")
		)
		(pad "151" smd rect
			(at 2.050034 -58.224928 270)
			(size 0.519938 1.4986)
			(layers "F.Cu" "F.Mask" "F.Paste")
			(net "GND")
		)
		(pad "152" smd rect
			(at 2.050034 -57.375044 270)
			(size 0.519938 1.4986)
			(layers "F.Cu" "F.Mask" "F.Paste")
			(net "M_E_CPU1_SA_DQ<2>")
		)
		(pad "153" smd rect
			(at 2.050034 -56.524906 270)
			(size 0.519938 1.4986)
			(layers "F.Cu" "F.Mask" "F.Paste")
			(net "GND")
		)
		(pad "154" smd rect
			(at 2.050034 -55.675022 270)
			(size 0.519938 1.4986)
			(layers "F.Cu" "F.Mask" "F.Paste")
			(net "M_E_CPU1_SA_DQ<3>")
		)
		(pad "155" smd rect
			(at 2.050034 -54.824884 270)
			(size 0.519938 1.4986)
			(layers "F.Cu" "F.Mask" "F.Paste")
			(net "GND")
		)
		(pad "156" smd rect
			(at 2.050034 -53.975 270)
			(size 0.519938 1.4986)
			(layers "F.Cu" "F.Mask" "F.Paste")
			(net "M_E_CPU1_SA_DQS_DN<5>")
		)
		(pad "157" smd rect
			(at 2.050034 -53.125116 270)
			(size 0.519938 1.4986)
			(layers "F.Cu" "F.Mask" "F.Paste")
			(net "M_E_CPU1_SA_DQS_DP<5>")
		)
		(pad "158" smd rect
			(at 2.050034 -52.274978 270)
			(size 0.519938 1.4986)
			(layers "F.Cu" "F.Mask" "F.Paste")
			(net "GND")
		)
		(pad "159" smd rect
			(at 2.050034 -51.425094 270)
			(size 0.519938 1.4986)
			(layers "F.Cu" "F.Mask" "F.Paste")
			(net "M_E_CPU1_SA_DQ<6>")
		)
		(pad "160" smd rect
			(at 2.050034 -50.574956 270)
			(size 0.519938 1.4986)
			(layers "F.Cu" "F.Mask" "F.Paste")
			(net "GND")
		)
		(pad "161" smd rect
			(at 2.050034 -49.725072 270)
			(size 0.519938 1.4986)
			(layers "F.Cu" "F.Mask" "F.Paste")
			(net "M_E_CPU1_SA_DQ<7>")
		)
		(pad "162" smd rect
			(at 2.050034 -48.874934 270)
			(size 0.519938 1.4986)
			(layers "F.Cu" "F.Mask" "F.Paste")
			(net "GND")
		)
		(pad "163" smd rect
			(at 2.050034 -48.02505 270)
			(size 0.519938 1.4986)
			(layers "F.Cu" "F.Mask" "F.Paste")
			(net "M_E_CPU1_SA_DQ<10>")
		)
		(pad "164" smd rect
			(at 2.050034 -47.174912 270)
			(size 0.519938 1.4986)
			(layers "F.Cu" "F.Mask" "F.Paste")
			(net "GND")
		)
		(pad "165" smd rect
			(at 2.050034 -46.325028 270)
			(size 0.519938 1.4986)
			(layers "F.Cu" "F.Mask" "F.Paste")
			(net "M_E_CPU1_SA_DQ<11>")
		)
		(pad "166" smd rect
			(at 2.050034 -45.47489 270)
			(size 0.519938 1.4986)
			(layers "F.Cu" "F.Mask" "F.Paste")
			(net "GND")
		)
		(pad "167" smd rect
			(at 2.050034 -44.625006 270)
			(size 0.519938 1.4986)
			(layers "F.Cu" "F.Mask" "F.Paste")
			(net "M_E_CPU1_SA_DQS_DN<6>")
		)
		(pad "168" smd rect
			(at 2.050034 -43.775122 270)
			(size 0.519938 1.4986)
			(layers "F.Cu" "F.Mask" "F.Paste")
			(net "M_E_CPU1_SA_DQS_DP<6>")
		)
		(pad "169" smd rect
			(at 2.050034 -42.924984 270)
			(size 0.519938 1.4986)
			(layers "F.Cu" "F.Mask" "F.Paste")
			(net "GND")
		)
		(pad "170" smd rect
			(at 2.050034 -42.0751 270)
			(size 0.519938 1.4986)
			(layers "F.Cu" "F.Mask" "F.Paste")
			(net "M_E_CPU1_SA_DQ<14>")
		)
		(pad "171" smd rect
			(at 2.050034 -41.224962 270)
			(size 0.519938 1.4986)
			(layers "F.Cu" "F.Mask" "F.Paste")
			(net "GND")
		)
		(pad "172" smd rect
			(at 2.050034 -40.375078 270)
			(size 0.519938 1.4986)
			(layers "F.Cu" "F.Mask" "F.Paste")
			(net "M_E_CPU1_SA_DQ<15>")
		)
		(pad "173" smd rect
			(at 2.050034 -39.52494 270)
			(size 0.519938 1.4986)
			(layers "F.Cu" "F.Mask" "F.Paste")
			(net "GND")
		)
		(pad "174" smd rect
			(at 2.050034 -38.675056 270)
			(size 0.519938 1.4986)
			(layers "F.Cu" "F.Mask" "F.Paste")
			(net "M_E_CPU1_SA_DQ<18>")
		)
		(pad "175" smd rect
			(at 2.050034 -37.824918 270)
			(size 0.519938 1.4986)
			(layers "F.Cu" "F.Mask" "F.Paste")
			(net "GND")
		)
		(pad "176" smd rect
			(at 2.050034 -36.975034 270)
			(size 0.519938 1.4986)
			(layers "F.Cu" "F.Mask" "F.Paste")
			(net "M_E_CPU1_SA_DQ<19>")
		)
		(pad "177" smd rect
			(at 2.050034 -36.124896 270)
			(size 0.519938 1.4986)
			(layers "F.Cu" "F.Mask" "F.Paste")
			(net "GND")
		)
		(pad "178" smd rect
			(at 2.050034 -35.275012 270)
			(size 0.519938 1.4986)
			(layers "F.Cu" "F.Mask" "F.Paste")
			(net "M_E_CPU1_SA_DQS_DN<7>")
		)
		(pad "179" smd rect
			(at 2.050034 -34.425128 270)
			(size 0.519938 1.4986)
			(layers "F.Cu" "F.Mask" "F.Paste")
			(net "M_E_CPU1_SA_DQS_DP<7>")
		)
		(pad "180" smd rect
			(at 2.050034 -33.57499 270)
			(size 0.519938 1.4986)
			(layers "F.Cu" "F.Mask" "F.Paste")
			(net "GND")
		)
		(pad "181" smd rect
			(at 2.050034 -32.725106 270)
			(size 0.519938 1.4986)
			(layers "F.Cu" "F.Mask" "F.Paste")
			(net "M_E_CPU1_SA_DQ<22>")
		)
		(pad "182" smd rect
			(at 2.050034 -31.874968 270)
			(size 0.519938 1.4986)
			(layers "F.Cu" "F.Mask" "F.Paste")
			(net "GND")
		)
		(pad "183" smd rect
			(at 2.050034 -31.025084 270)
			(size 0.519938 1.4986)
			(layers "F.Cu" "F.Mask" "F.Paste")
			(net "M_E_CPU1_SA_DQ<23>")
		)
		(pad "184" smd rect
			(at 2.050034 -30.174946 270)
			(size 0.519938 1.4986)
			(layers "F.Cu" "F.Mask" "F.Paste")
			(net "GND")
		)
		(pad "185" smd rect
			(at 2.050034 -29.325062 270)
			(size 0.519938 1.4986)
			(layers "F.Cu" "F.Mask" "F.Paste")
			(net "M_E_CPU1_SA_DQ<26>")
		)
		(pad "186" smd rect
			(at 2.050034 -28.474924 270)
			(size 0.519938 1.4986)
			(layers "F.Cu" "F.Mask" "F.Paste")
			(net "GND")
		)
		(pad "187" smd rect
			(at 2.050034 -27.62504 270)
			(size 0.519938 1.4986)
			(layers "F.Cu" "F.Mask" "F.Paste")
			(net "M_E_CPU1_SA_DQ<27>")
		)
		(pad "188" smd rect
			(at 2.050034 -26.774902 270)
			(size 0.519938 1.4986)
			(layers "F.Cu" "F.Mask" "F.Paste")
			(net "GND")
		)
		(pad "189" smd rect
			(at 2.050034 -25.925018 270)
			(size 0.519938 1.4986)
			(layers "F.Cu" "F.Mask" "F.Paste")
			(net "M_E_CPU1_SA_DQS_DN<8>")
		)
		(pad "190" smd rect
			(at 2.050034 -25.07488 270)
			(size 0.519938 1.4986)
			(layers "F.Cu" "F.Mask" "F.Paste")
			(net "M_E_CPU1_SA_DQS_DP<8>")
		)
		(pad "191" smd rect
			(at 2.050034 -24.224996 270)
			(size 0.519938 1.4986)
			(layers "F.Cu" "F.Mask" "F.Paste")
			(net "GND")
		)
		(pad "192" smd rect
			(at 2.050034 -23.375112 270)
			(size 0.519938 1.4986)
			(layers "F.Cu" "F.Mask" "F.Paste")
			(net "M_E_CPU1_SA_DQ<30>")
		)
		(pad "193" smd rect
			(at 2.050034 -22.524974 270)
			(size 0.519938 1.4986)
			(layers "F.Cu" "F.Mask" "F.Paste")
			(net "GND")
		)
		(pad "194" smd rect
			(at 2.050034 -21.67509 270)
			(size 0.519938 1.4986)
			(layers "F.Cu" "F.Mask" "F.Paste")
			(net "M_E_CPU1_SA_DQ<31>")
		)
		(pad "195" smd rect
			(at 2.050034 -20.824952 270)
			(size 0.519938 1.4986)
			(layers "F.Cu" "F.Mask" "F.Paste")
			(net "GND")
		)
		(pad "196" smd rect
			(at 2.050034 -19.975068 270)
			(size 0.519938 1.4986)
			(layers "F.Cu" "F.Mask" "F.Paste")
			(net "M_E_CPU1_SA_CB<2>")
		)
		(pad "197" smd rect
			(at 2.050034 -19.12493 270)
			(size 0.519938 1.4986)
			(layers "F.Cu" "F.Mask" "F.Paste")
			(net "GND")
		)
		(pad "198" smd rect
			(at 2.050034 -18.275046 270)
			(size 0.519938 1.4986)
			(layers "F.Cu" "F.Mask" "F.Paste")
			(net "M_E_CPU1_SA_CB<3>")
		)
		(pad "199" smd rect
			(at 2.050034 -17.424908 270)
			(size 0.519938 1.4986)
			(layers "F.Cu" "F.Mask" "F.Paste")
			(net "GND")
		)
		(pad "200" smd rect
			(at 2.050034 -16.575024 270)
			(size 0.519938 1.4986)
			(layers "F.Cu" "F.Mask" "F.Paste")
			(net "M_E_CPU1_SA_DQS_DN<9>")
		)
		(pad "201" smd rect
			(at 2.050034 -15.724886 270)
			(size 0.519938 1.4986)
			(layers "F.Cu" "F.Mask" "F.Paste")
			(net "M_E_CPU1_SA_DQS_DP<9>")
		)
		(pad "202" smd rect
			(at 2.050034 -14.875002 270)
			(size 0.519938 1.4986)
			(layers "F.Cu" "F.Mask" "F.Paste")
			(net "GND")
		)
		(pad "203" smd rect
			(at 2.050034 -14.025118 270)
			(size 0.519938 1.4986)
			(layers "F.Cu" "F.Mask" "F.Paste")
			(net "M_E_CPU1_SA_CB<6>")
		)
		(pad "204" smd rect
			(at 2.050034 -13.17498 270)
			(size 0.519938 1.4986)
			(layers "F.Cu" "F.Mask" "F.Paste")
			(net "GND")
		)
		(pad "205" smd rect
			(at 2.050034 -12.325096 270)
			(size 0.519938 1.4986)
			(layers "F.Cu" "F.Mask" "F.Paste")
			(net "M_E_CPU1_SA_CB<7>")
		)
		(pad "206" smd rect
			(at 2.050034 -11.474958 270)
			(size 0.519938 1.4986)
			(layers "F.Cu" "F.Mask" "F.Paste")
			(net "GND")
		)
		(pad "207" smd rect
			(at 2.050034 -10.625074 270)
			(size 0.519938 1.4986)
			(layers "F.Cu" "F.Mask" "F.Paste")
			(net "RST_M_EF_CPU1_FPGA_N")
		)
		(pad "208" smd rect
			(at 2.050034 -9.774936 270)
			(size 0.519938 1.4986)
			(layers "F.Cu" "F.Mask" "F.Paste")
			(net "GND")
		)
		(pad "209" smd rect
			(at 2.050034 -8.925052 270)
			(size 0.519938 1.4986)
			(layers "F.Cu" "F.Mask" "F.Paste")
			(net "M_E_CPU1_SA_CS_N<3>")
		)
		(pad "210" smd rect
			(at 2.050034 -8.074914 270)
			(size 0.519938 1.4986)
			(layers "F.Cu" "F.Mask" "F.Paste")
			(net "GND")
		)
		(pad "211" smd rect
			(at 2.050034 -7.22503 270)
			(size 0.519938 1.4986)
			(layers "F.Cu" "F.Mask" "F.Paste")
			(net "M_E_CPU1_SA_CA<1>")
		)
		(pad "212" smd rect
			(at 2.050034 -6.374892 270)
			(size 0.519938 1.4986)
			(layers "F.Cu" "F.Mask" "F.Paste")
			(net "GND")
		)
		(pad "213" smd rect
			(at 2.050034 -5.525008 270)
			(size 0.519938 1.4986)
			(layers "F.Cu" "F.Mask" "F.Paste")
			(net "M_E_CPU1_SA_CA<3>")
		)
		(pad "214" smd rect
			(at 2.050034 -4.675124 270)
			(size 0.519938 1.4986)
			(layers "F.Cu" "F.Mask" "F.Paste")
			(net "GND")
		)
		(pad "215" smd rect
			(at 2.050034 -3.824986 270)
			(size 0.519938 1.4986)
			(layers "F.Cu" "F.Mask" "F.Paste")
			(net "M_E_CPU1_SA_CA<5>")
		)
		(pad "216" smd rect
			(at 2.050034 -2.975102 270)
			(size 0.519938 1.4986)
			(layers "F.Cu" "F.Mask" "F.Paste")
			(net "GND")
		)
		(pad "217" smd rect
			(at 2.050034 -2.124964 270)
			(size 0.519938 1.4986)
			(layers "F.Cu" "F.Mask" "F.Paste")
			(net "M_E_CPU1_CLK_DP<1>")
		)
		(pad "218" smd rect
			(at 2.050034 -1.27508 270)
			(size 0.519938 1.4986)
			(layers "F.Cu" "F.Mask" "F.Paste")
			(net "M_E_CPU1_CLK_DN<1>")
		)
		(pad "219" smd rect
			(at 2.050034 -0.424942 270)
			(size 0.519938 1.4986)
			(layers "F.Cu" "F.Mask" "F.Paste")
			(net "GND")
		)
		(pad "220" smd rect
			(at 2.050034 5.525008 270)
			(size 0.519938 1.4986)
			(layers "F.Cu" "F.Mask" "F.Paste")
			(net "TP_CHE_CPU1_DIMM2_FRU_4")
		)
		(pad "221" smd rect
			(at 2.050034 6.374892 270)
			(size 0.519938 1.4986)
			(layers "F.Cu" "F.Mask" "F.Paste")
			(net "M_E_CPU1_SB_CA<1>")
		)
		(pad "222" smd rect
			(at 2.050034 7.22503 270)
			(size 0.519938 1.4986)
			(layers "F.Cu" "F.Mask" "F.Paste")
			(net "GND")
		)
		(pad "223" smd rect
			(at 2.050034 8.074914 270)
			(size 0.519938 1.4986)
			(layers "F.Cu" "F.Mask" "F.Paste")
			(net "M_E_CPU1_SB_CA<3>")
		)
		(pad "224" smd rect
			(at 2.050034 8.925052 270)
			(size 0.519938 1.4986)
			(layers "F.Cu" "F.Mask" "F.Paste")
			(net "GND")
		)
	)
)
